# T6G (Grand Teton) — schematic netlist excerpt (pin names and nets, part order shuffled) for the footprints in the layout excerpt that follows; sources: Cadence DE-HDL packaged netlist, KiCad conversion of 04192023_DAF0TMB3IC0_F0TG_MB_C_brd_V02_OCP.brd

C2380  Q_CAP  22UF 4V 20% X6S  pkg C0402  page 73 : A = PVDDCR_CPU1_P1 ; B = GND
PC485_1  Q_CAP  22UF 16V 20% X6S  pkg C0805  page 194 : A = SW_P12V_AUX_PVDDCR_CPU0_P0_FLT ; B = GND
C2331  Q_CAP  22UF 4V 20% X6S  pkg C0402  page 73 : A = PVDDCR_CPU0_P1 ; B = GND

(kicad_pcb
	(version 20260206)
	(generator "pcbnew")
	(generator_version "10.0")
	(general
		(thickness 1.6)
		(legacy_teardrops no)
	)
	(paper "A4")
	(title_block
		(title "04192023_DAF0TMB3IC0_F0TG_MB_C_brd_V02_OCP.brd")
		(comment 1 "Grand Teton / footprints 6715-6717 of 8354")
	)
	(layers
		(0 "F.Cu" signal "TOP")
		(4 "In1.Cu" signal "GND")
		(6 "In2.Cu" signal "IN1")
		(8 "In3.Cu" signal "GND1")
		(10 "In4.Cu" signal "IN2")
		(12 "In5.Cu" signal "GND2")
		(14 "In6.Cu" signal "IN3")
		(16 "In7.Cu" signal "GND3")
		(18 "In8.Cu" signal "VCC")
		(20 "In9.Cu" signal "VCC1")
		(22 "In10.Cu" signal "GND4")
		(24 "In11.Cu" signal "IN4")
		(26 "In12.Cu" signal "GND5")
		(28 "In13.Cu" signal "IN5")
		(30 "In14.Cu" signal "GND6")
		(32 "In15.Cu" signal "IN6")
		(34 "In16.Cu" signal "GND7")
		(2 "B.Cu" signal "BOTTOM")
		(9 "F.Adhes" user "F.Adhesive")
		(11 "B.Adhes" user "B.Adhesive")
		(13 "F.Paste" user "Package Geometry/Pastemask Top")
		(15 "B.Paste" user "Package Geometry/Pastemask Bottom")
		(5 "F.SilkS" user "Ref Des/Silkscreen Top")
		(7 "B.SilkS" user "Ref Des/Silkscreen Bottom")
		(1 "F.Mask" user "Board Geometry/Soldermask Top")
		(3 "B.Mask" user "Board Geometry/Soldermask Bottom")
		(17 "Dwgs.User" user "User.Drawings")
		(19 "Cmts.User" user "User.Comments")
		(21 "Eco1.User" user "User.Eco1")
		(23 "Eco2.User" user "User.Eco2")
		(25 "Edge.Cuts" user "Board Geometry/Outline")
		(27 "Margin" user)
		(31 "F.CrtYd" user "Package Geometry/Place Bound Top")
		(29 "B.CrtYd" user "Package Geometry/Place Bound Bottom")
		(35 "F.Fab" user "Ref Des/Assembly Top")
		(33 "B.Fab" user "Ref Des/Assembly Bottom")
	)
	(footprint ""
		(layer "B.Cu")
		(at 116.499386 -248.479564)
		(property "Reference" "C2331"
			(at 0 0 0)
			(layer "B.SilkS")
			(hide yes)
			(effects
				(font
					(size 1.27 1.27)
				)
				(justify mirror)
			)
		)
		(property "Value" ""
			(at 0 0 0)
			(layer "B.Fab")
			(effects
				(font
					(size 1.27 1.27)
				)
				(justify mirror)
			)
		)
		(duplicate_pad_numbers_are_jumpers no)
		(fp_line
			(start -0.7874 -0.4064)
			(end -0.7874 0.4064)
			(stroke
				(width 0.1524)
				(type default)
			)
			(layer "B.SilkS")
		)
		(fp_line
			(start -0.7874 0.4064)
			(end 0.7874 0.4064)
			(stroke
				(width 0.1524)
				(type default)
			)
			(layer "B.SilkS")
		)
		(fp_line
			(start 0.7874 -0.4064)
			(end -0.7874 -0.4064)
			(stroke
				(width 0.1524)
				(type default)
			)
			(layer "B.SilkS")
		)
		(fp_line
			(start 0.7874 0.4064)
			(end 0.7874 -0.4064)
			(stroke
				(width 0.1524)
				(type default)
			)
			(layer "B.SilkS")
		)
		(fp_line
			(start -0.67945 -0.3048)
			(end -0.67945 0.3048)
			(stroke
				(width 0.1)
				(type default)
			)
			(layer "B.Fab")
		)
		(fp_line
			(start -0.67945 0.3048)
			(end -0.120396 0.3048)
			(stroke
				(width 0.1)
				(type default)
			)
			(layer "B.Fab")
		)
		(fp_line
			(start -0.12065 -0.3048)
			(end -0.67945 -0.3048)
			(stroke
				(width 0.1)
				(type default)
			)
			(layer "B.Fab")
		)
		(fp_line
			(start -0.12065 -0.2794)
			(end -0.12065 -0.3048)
			(stroke
				(width 0.1)
				(type default)
			)
			(layer "B.Fab")
		)
		(fp_line
			(start -0.120396 0.2794)
			(end 0.12065 0.2794)
			(stroke
				(width 0.1)
				(type default)
			)
			(layer "B.Fab")
		)
		(fp_line
			(start -0.120396 0.3048)
			(end -0.120396 0.2794)
			(stroke
				(width 0.1)
				(type default)
			)
			(layer "B.Fab")
		)
		(fp_line
			(start 0.12065 -0.305054)
			(end 0.12065 -0.2794)
			(stroke
				(width 0.1)
				(type default)
			)
			(layer "B.Fab")
		)
		(fp_line
			(start 0.12065 -0.2794)
			(end -0.12065 -0.2794)
			(stroke
				(width 0.1)
				(type default)
			)
			(layer "B.Fab")
		)
		(fp_line
			(start 0.12065 0.2794)
			(end 0.12065 0.3048)
			(stroke
				(width 0.1)
				(type default)
			)
			(layer "B.Fab")
		)
		(fp_line
			(start 0.12065 0.3048)
			(end 0.67945 0.3048)
			(stroke
				(width 0.1)
				(type default)
			)
			(layer "B.Fab")
		)
		(fp_line
			(start 0.67945 -0.305054)
			(end 0.12065 -0.305054)
			(stroke
				(width 0.1)
				(type default)
			)
			(layer "B.Fab")
		)
		(fp_line
			(start 0.67945 0.3048)
			(end 0.67945 -0.305054)
			(stroke
				(width 0.1)
				(type default)
			)
			(layer "B.Fab")
		)
		(pad "1" smd circle
			(at 0.40005 0 180)
			(size 0 0)
			(layers "B.Cu" "B.Mask" "B.Paste")
			(net "PVDDCR_CPU0_P1")
		)
		(pad "2" smd circle
			(at -0.40005 0 180)
			(size 0 0)
			(layers "B.Cu" "B.Mask" "B.Paste")
			(net "GND")
		)
	)
	(footprint ""
		(layer "B.Cu")
		(at 108.371386 -267.529564)
		(property "Reference" "C2380"
			(at 0 0 0)
			(layer "B.SilkS")
			(hide yes)
			(effects
				(font
					(size 1.27 1.27)
				)
				(justify mirror)
			)
		)
		(property "Value" ""
			(at 0 0 0)
			(layer "B.Fab")
			(effects
				(font
					(size 1.27 1.27)
				)
				(justify mirror)
			)
		)
		(duplicate_pad_numbers_are_jumpers no)
		(fp_line
			(start -0.7874 -0.4064)
			(end -0.7874 0.4064)
			(stroke
				(width 0.1524)
				(type default)
			)
			(layer "B.SilkS")
		)
		(fp_line
			(start -0.7874 0.4064)
			(end 0.7874 0.4064)
			(stroke
				(width 0.1524)
				(type default)
			)
			(layer "B.SilkS")
		)
		(fp_line
			(start 0.7874 -0.4064)
			(end -0.7874 -0.4064)
			(stroke
				(width 0.1524)
				(type default)
			)
			(layer "B.SilkS")
		)
		(fp_line
			(start 0.7874 0.4064)
			(end 0.7874 -0.4064)
			(stroke
				(width 0.1524)
				(type default)
			)
			(layer "B.SilkS")
		)
		(fp_line
			(start -0.67945 -0.3048)
			(end -0.67945 0.3048)
			(stroke
				(width 0.1)
				(type default)
			)
			(layer "B.Fab")
		)
		(fp_line
			(start -0.67945 0.3048)
			(end -0.120396 0.3048)
			(stroke
				(width 0.1)
				(type default)
			)
			(layer "B.Fab")
		)
		(fp_line
			(start -0.12065 -0.3048)
			(end -0.67945 -0.3048)
			(stroke
				(width 0.1)
				(type default)
			)
			(layer "B.Fab")
		)
		(fp_line
			(start -0.12065 -0.2794)
			(end -0.12065 -0.3048)
			(stroke
				(width 0.1)
				(type default)
			)
			(layer "B.Fab")
		)
		(fp_line
			(start -0.120396 0.2794)
			(end 0.12065 0.2794)
			(stroke
				(width 0.1)
				(type default)
			)
			(layer "B.Fab")
		)
		(fp_line
			(start -0.120396 0.3048)
			(end -0.120396 0.2794)
			(stroke
				(width 0.1)
				(type default)
			)
			(layer "B.Fab")
		)
		(fp_line
			(start 0.12065 -0.305054)
			(end 0.12065 -0.2794)
			(stroke
				(width 0.1)
				(type default)
			)
			(layer "B.Fab")
		)
		(fp_line
			(start 0.12065 -0.2794)
			(end -0.12065 -0.2794)
			(stroke
				(width 0.1)
				(type default)
			)
			(layer "B.Fab")
		)
		(fp_line
			(start 0.12065 0.2794)
			(end 0.12065 0.3048)
			(stroke
				(width 0.1)
				(type default)
			)
			(layer "B.Fab")
		)
		(fp_line
			(start 0.12065 0.3048)
			(end 0.67945 0.3048)
			(stroke
				(width 0.1)
				(type default)
			)
			(layer "B.Fab")
		)
		(fp_line
			(start 0.67945 -0.305054)
			(end 0.12065 -0.305054)
			(stroke
				(width 0.1)
				(type default)
			)
			(layer "B.Fab")
		)
		(fp_line
			(start 0.67945 0.3048)
			(end 0.67945 -0.305054)
			(stroke
				(width 0.1)
				(type default)
			)
			(layer "B.Fab")
		)
		(pad "1" smd circle
			(at 0.40005 0 180)
			(size 0 0)
			(layers "B.Cu" "B.Mask" "B.Paste")
			(net "PVDDCR_CPU1_P1")
		)
		(pad "2" smd circle
			(at -0.40005 0 180)
			(size 0 0)
			(layers "B.Cu" "B.Mask" "B.Paste")
			(net "GND")
		)
	)
	(footprint ""
		(layer "B.Cu")
		(at 363.287056 -177.894996 -90)
		(property "Reference" "PC485_1"
			(at 0 0 90)
			(layer "B.SilkS")
			(hide yes)
			(effects
				(font
					(size 1.27 1.27)
				)
				(justify mirror)
			)
		)
		(property "Value" ""
			(at 0 0 90)
			(layer "B.Fab")
			(effects
				(font
					(size 1.27 1.27)
				)
				(justify mirror)
			)
		)
		(duplicate_pad_numbers_are_jumpers no)
		(fp_line
			(start -1.524 0.762)
			(end 1.524 0.762)
			(stroke
				(width 0.1524)
				(type default)
			)
			(layer "B.SilkS")
		)
		(fp_line
			(start 1.524 0.762)
			(end 1.524 -0.762)
			(stroke
				(width 0.1524)
				(type default)
			)
			(layer "B.SilkS")
		)
		(fp_line
			(start -1.524 -0.762)
			(end -1.524 0.762)
			(stroke
				(width 0.1524)
				(type default)
			)
			(layer "B.SilkS")
		)
		(fp_line
			(start 1.524 -0.762)
			(end -1.524 -0.762)
			(stroke
				(width 0.1524)
				(type default)
			)
			(layer "B.SilkS")
		)
		(fp_line
			(start -1.1049 0.724916)
			(end -1.1049 -0.724916)
			(stroke
				(width 0.1)
				(type default)
			)
			(layer "B.Fab")
		)
		(fp_line
			(start 1.1049 0.724916)
			(end -1.1049 0.724916)
			(stroke
				(width 0.1)
				(type default)
			)
			(layer "B.Fab")
		)
		(fp_line
			(start -1.1049 -0.724916)
			(end 1.1049 -0.724916)
			(stroke
				(width 0.1)
				(type default)
			)
			(layer "B.Fab")
		)
		(fp_line
			(start 1.1049 -0.724916)
			(end 1.1049 0.724916)
			(stroke
				(width 0.1)
				(type default)
			)
			(layer "B.Fab")
		)
		(pad "1" smd rect
			(at 0.889 0 270)
			(size 1.016 1.27)
			(layers "B.Cu" "B.Mask" "B.Paste")
			(net "SW_P12V_AUX_PVDDCR_CPU0_P0_FLT")
		)
		(pad "2" smd rect
			(at -0.889 0 270)
			(size 1.016 1.27)
			(layers "B.Cu" "B.Mask" "B.Paste")
			(net "GND")
		)
	)
)
